(kicad_pcb
	(version 20260206)
	(generator "pcbnew")
	(generator_version "10.0")
	(general
		(thickness 1.6)
		(legacy_teardrops no)
	)
	(paper "A4")
	(title_block
		(title "panther-plus-userver — 13130-1b_20150205.brd")
		(comment 1 "Honey Badger (Wiwynn) / footprints 713-721 of 1509")
	)
	(layers
		(0 "F.Cu" signal "TOP")
		(4 "In1.Cu" signal "L2")
		(6 "In2.Cu" signal "L3")
		(8 "In3.Cu" signal "L4")
		(10 "In4.Cu" signal "L5")
		(12 "In5.Cu" signal "L6")
		(14 "In6.Cu" signal "L7")
		(16 "In7.Cu" signal "L8")
		(18 "In8.Cu" signal "L9")
		(20 "In9.Cu" signal "L10")
		(22 "In10.Cu" signal "L11")
		(2 "B.Cu" signal "BOTTOM")
		(9 "F.Adhes" user "F.Adhesive")
		(11 "B.Adhes" user "B.Adhesive")
		(13 "F.Paste" user "Package Geometry/Pastemask Top")
		(15 "B.Paste" user "Package Geometry/Pastemask Bottom")
		(5 "F.SilkS" user "Ref Des/Silkscreen Top")
		(7 "B.SilkS" user "Ref Des/Silkscreen Bottom")
		(1 "F.Mask" user "Board Geometry/Soldermask Top")
		(3 "B.Mask" user "Board Geometry/Soldermask Bottom")
		(17 "Dwgs.User" user "User.Drawings")
		(19 "Cmts.User" user "User.Comments")
		(21 "Eco1.User" user "User.Eco1")
		(23 "Eco2.User" user "User.Eco2")
		(25 "Edge.Cuts" user "Board Geometry/Outline")
		(27 "Margin" user)
		(31 "F.CrtYd" user "Package Geometry/Place Bound Top")
		(29 "B.CrtYd" user "Package Geometry/Place Bound Bottom")
		(35 "F.Fab" user "Ref Des/Assembly Top")
		(33 "B.Fab" user "Ref Des/Assembly Bottom")
	)
	(footprint ""
		(layer "F.Cu")
		(at 71.882 -18.288 -90)
		(property "Reference" "R442"
			(at 0 0 270)
			(layer "F.SilkS")
			(hide yes)
			(effects
				(font
					(size 1.27 1.27)
				)
			)
		)
		(property "Value" "0R2J-2-GP"
			(at 1.7907 -1.1176 270)
			(unlocked yes)
			(layer "F.Fab")
			(hide yes)
			(effects
				(font
					(size 1.016 1.016)
					(thickness 0.1524)
				)
			)
		)
		(property "Device Type" "R402H16"
			(at 1.7907 -2.6416 270)
			(unlocked yes)
			(layer "F.Fab")
			(hide yes)
			(effects
				(font
					(size 1.016 1.016)
					(thickness 0.1524)
				)
			)
		)
		(duplicate_pad_numbers_are_jumpers no)
		(fp_rect
			(start -0.381 0.8382)
			(end 0.381 -0.8382)
			(stroke
				(width 0)
				(type default)
			)
			(fill no)
			(layer "F.CrtYd")
		)
		(fp_rect
			(start -0.381 0.8382)
			(end 0.381 -0.8382)
			(stroke
				(width 0)
				(type default)
			)
			(fill no)
			(layer "F.Fab")
		)
		(pad "1" smd custom
			(at 0 -0.4318 270)
			(size 0.127 0.127)
			(layers "F.Cu" "F.Mask" "F.Paste")
			(net "CPU_TXD")
			(options
				(clearance outline)
				(anchor circle)
			)
			(primitives
				(gr_poly
					(pts
						(arc
							(start -0.2032 -0.2794)
							(mid -0.239121 -0.264521)
							(end -0.254 -0.2286)
						)
						(arc
							(start -0.254 0.2286)
							(mid -0.239121 0.264521)
							(end -0.2032 0.2794)
						)
						(arc
							(start 0.2032 0.2794)
							(mid 0.239121 0.264521)
							(end 0.254 0.2286)
						)
						(arc
							(start 0.254 -0.2286)
							(mid 0.239121 -0.264521)
							(end 0.2032 -0.2794)
						)
					)
					(width 0)
					(fill yes)
				)
			)
		)
		(pad "2" smd custom
			(at 0 0.4318 270)
			(size 0.127 0.127)
			(layers "F.Cu" "F.Mask" "F.Paste")
			(net "GF_CPU_TXD")
			(options
				(clearance outline)
				(anchor circle)
			)
			(primitives
				(gr_poly
					(pts
						(arc
							(start -0.2032 -0.2794)
							(mid -0.239121 -0.264521)
							(end -0.254 -0.2286)
						)
						(arc
							(start -0.254 0.2286)
							(mid -0.239121 0.264521)
							(end -0.2032 0.2794)
						)
						(arc
							(start 0.2032 0.2794)
							(mid 0.239121 0.264521)
							(end 0.254 0.2286)
						)
						(arc
							(start 0.254 -0.2286)
							(mid 0.239121 -0.264521)
							(end 0.2032 -0.2794)
						)
					)
					(width 0)
					(fill yes)
				)
			)
		)
	)
	(footprint ""
		(layer "F.Cu")
		(at 57.404 -54.356)
		(property "Reference" "PR157"
			(at 0 0 0)
			(layer "F.SilkS")
			(hide yes)
			(effects
				(font
					(size 1.27 1.27)
				)
			)
		)
		(property "Value" "0R2J-2-GP"
			(at 1.7907 -1.1176 0)
			(unlocked yes)
			(layer "F.Fab")
			(hide yes)
			(effects
				(font
					(size 1.016 1.016)
					(thickness 0.1524)
				)
			)
		)
		(property "Device Type" "R402H16"
			(at 1.7907 -2.6416 0)
			(unlocked yes)
			(layer "F.Fab")
			(hide yes)
			(effects
				(font
					(size 1.016 1.016)
					(thickness 0.1524)
				)
			)
		)
		(duplicate_pad_numbers_are_jumpers no)
		(fp_rect
			(start -0.381 0.8382)
			(end 0.381 -0.8382)
			(stroke
				(width 0)
				(type default)
			)
			(fill no)
			(layer "F.CrtYd")
		)
		(fp_rect
			(start -0.381 0.8382)
			(end 0.381 -0.8382)
			(stroke
				(width 0)
				(type default)
			)
			(fill no)
			(layer "F.Fab")
		)
		(pad "1" smd custom
			(at 0 -0.4318)
			(size 0.127 0.127)
			(layers "F.Cu" "F.Mask" "F.Paste")
			(net "VR_FB_R_P1V0_STBY")
			(options
				(clearance outline)
				(anchor circle)
			)
			(primitives
				(gr_poly
					(pts
						(arc
							(start -0.2032 -0.2794)
							(mid -0.239121 -0.264521)
							(end -0.254 -0.2286)
						)
						(arc
							(start -0.254 0.2286)
							(mid -0.239121 0.264521)
							(end -0.2032 0.2794)
						)
						(arc
							(start 0.2032 0.2794)
							(mid 0.239121 0.264521)
							(end 0.254 0.2286)
						)
						(arc
							(start 0.254 -0.2286)
							(mid 0.239121 -0.264521)
							(end 0.2032 -0.2794)
						)
					)
					(width 0)
					(fill yes)
				)
			)
		)
		(pad "2" smd custom
			(at 0 0.4318)
			(size 0.127 0.127)
			(layers "F.Cu" "F.Mask" "F.Paste")
			(net "P1V0_STBY_VOUT")
			(options
				(clearance outline)
				(anchor circle)
			)
			(primitives
				(gr_poly
					(pts
						(arc
							(start -0.2032 -0.2794)
							(mid -0.239121 -0.264521)
							(end -0.254 -0.2286)
						)
						(arc
							(start -0.254 0.2286)
							(mid -0.239121 0.264521)
							(end -0.2032 0.2794)
						)
						(arc
							(start 0.2032 0.2794)
							(mid 0.239121 0.264521)
							(end 0.254 0.2286)
						)
						(arc
							(start 0.254 -0.2286)
							(mid 0.239121 -0.264521)
							(end 0.2032 -0.2794)
						)
					)
					(width 0)
					(fill yes)
				)
			)
		)
	)
	(footprint ""
		(layer "F.Cu")
		(at 70.2818 -46.8376 180)
		(property "Reference" "R62"
			(at 0 0 180)
			(layer "F.SilkS")
			(hide yes)
			(effects
				(font
					(size 1.27 1.27)
				)
			)
		)
		(property "Value" "0R2J-2-GP"
			(at 0.064008 -3.993896 180)
			(unlocked yes)
			(layer "F.Fab")
			(hide yes)
			(effects
				(font
					(size 1.016 1.016)
					(thickness 0.1524)
				)
			)
		)
		(property "Device Type" "R402H16"
			(at 0.064008 -5.517896 180)
			(unlocked yes)
			(layer "F.Fab")
			(hide yes)
			(effects
				(font
					(size 1.016 1.016)
					(thickness 0.1524)
				)
			)
		)
		(duplicate_pad_numbers_are_jumpers no)
		(fp_rect
			(start -0.381 0.8382)
			(end 0.381 -0.8382)
			(stroke
				(width 0)
				(type default)
			)
			(fill no)
			(layer "F.CrtYd")
		)
		(fp_rect
			(start -0.381 0.8382)
			(end 0.381 -0.8382)
			(stroke
				(width 0)
				(type default)
			)
			(fill no)
			(layer "F.Fab")
		)
		(pad "1" smd custom
			(at 0 -0.4318 180)
			(size 0.127 0.127)
			(layers "F.Cu" "F.Mask" "F.Paste")
			(net "SMB_PECI_LV_R_DATA")
			(options
				(clearance outline)
				(anchor circle)
			)
			(primitives
				(gr_poly
					(pts
						(arc
							(start -0.2032 -0.2794)
							(mid -0.239121 -0.264521)
							(end -0.254 -0.2286)
						)
						(arc
							(start -0.254 0.2286)
							(mid -0.239121 0.264521)
							(end -0.2032 0.2794)
						)
						(arc
							(start 0.2032 0.2794)
							(mid 0.239121 0.264521)
							(end 0.254 0.2286)
						)
						(arc
							(start 0.254 -0.2286)
							(mid 0.239121 -0.264521)
							(end 0.2032 -0.2794)
						)
					)
					(width 0)
					(fill yes)
				)
			)
		)
		(pad "2" smd custom
			(at 0 0.4318 180)
			(size 0.127 0.127)
			(layers "F.Cu" "F.Mask" "F.Paste")
			(net "SMB_PECI_LV_DATA")
			(options
				(clearance outline)
				(anchor circle)
			)
			(primitives
				(gr_poly
					(pts
						(arc
							(start -0.2032 -0.2794)
							(mid -0.239121 -0.264521)
							(end -0.254 -0.2286)
						)
						(arc
							(start -0.254 0.2286)
							(mid -0.239121 0.264521)
							(end -0.2032 0.2794)
						)
						(arc
							(start 0.2032 0.2794)
							(mid 0.239121 0.264521)
							(end 0.254 0.2286)
						)
						(arc
							(start 0.254 -0.2286)
							(mid 0.239121 -0.264521)
							(end 0.2032 -0.2794)
						)
					)
					(width 0)
					(fill yes)
				)
			)
		)
	)
	(footprint ""
		(layer "F.Cu")
		(at 204.7748 -26.162 90)
		(property "Reference" "TP18"
			(at 0 0 90)
			(layer "F.SilkS")
			(hide yes)
			(effects
				(font
					(size 1.27 1.27)
				)
			)
		)
		(property "Value" "TPAD32-GP"
			(at 0 -3.166364 90)
			(unlocked yes)
			(layer "F.Fab")
			(hide yes)
			(effects
				(font
					(size 1.016 1.016)
					(thickness 0.1524)
				)
			)
		)
		(property "Device Type" "TPAD32"
			(at 0 -4.690618 90)
			(unlocked yes)
			(layer "F.Fab")
			(hide yes)
			(effects
				(font
					(size 1.016 1.016)
					(thickness 0.1524)
				)
			)
		)
		(duplicate_pad_numbers_are_jumpers no)
		(fp_poly
			(pts
				(arc
					(start 0 0.7112)
					(mid 0 -0.7112)
					(end 0 0.7112)
				)
			)
			(stroke
				(width 0)
				(type default)
			)
			(fill no)
			(layer "F.CrtYd")
		)
		(fp_poly
			(pts
				(arc
					(start 0 0.7112)
					(mid 0 -0.7112)
					(end 0 0.7112)
				)
			)
			(stroke
				(width 0)
				(type default)
			)
			(fill no)
			(layer "F.Fab")
		)
		(pad "1" smd circle
			(at 0 0 90)
			(size 0.8128 0.8128)
			(layers "F.Cu" "F.Mask" "F.Paste")
			(net "JTAG_PLD_TCK")
		)
	)
	(footprint ""
		(layer "F.Cu")
		(at 169.926 -43.561 -90)
		(property "Reference" "PC211"
			(at 0 0 270)
			(layer "F.SilkS")
			(hide yes)
			(effects
				(font
					(size 1.27 1.27)
				)
			)
		)
		(property "Value" "SCD01U16V2KX-3GP"
			(at 1.8923 -1.2065 270)
			(unlocked yes)
			(layer "F.Fab")
			(hide yes)
			(effects
				(font
					(size 1.016 1.016)
					(thickness 0.1524)
				)
			)
		)
		(property "Device Type" "C402H22"
			(at 1.8923 -2.7305 270)
			(unlocked yes)
			(layer "F.Fab")
			(hide yes)
			(effects
				(font
					(size 1.016 1.016)
					(thickness 0.1524)
				)
			)
		)
		(duplicate_pad_numbers_are_jumpers no)
		(fp_rect
			(start -0.381 0.7366)
			(end 0.381 -0.7366)
			(stroke
				(width 0)
				(type default)
			)
			(fill no)
			(layer "F.CrtYd")
		)
		(fp_rect
			(start -0.381 0.7366)
			(end 0.381 -0.7366)
			(stroke
				(width 0)
				(type default)
			)
			(fill no)
			(layer "F.Fab")
		)
		(pad "1" smd custom
			(at 0 -0.4572 270)
			(size 0.1143 0.1143)
			(layers "F.Cu" "F.Mask" "F.Paste")
			(net "P2V5_STBY_BYPASS")
			(options
				(clearance outline)
				(anchor circle)
			)
			(primitives
				(gr_poly
					(pts
						(arc
							(start -0.254 -0.1778)
							(mid -0.239121 -0.213721)
							(end -0.2032 -0.2286)
						)
						(arc
							(start 0.2032 -0.2286)
							(mid 0.239121 -0.213721)
							(end 0.254 -0.1778)
						)
						(arc
							(start 0.254 0.1778)
							(mid 0.239121 0.213721)
							(end 0.2032 0.2286)
						)
						(arc
							(start -0.2032 0.2286)
							(mid -0.239121 0.213721)
							(end -0.254 0.1778)
						)
					)
					(width 0)
					(fill yes)
				)
			)
		)
		(pad "2" smd custom
			(at 0 0.4572 270)
			(size 0.1143 0.1143)
			(layers "F.Cu" "F.Mask" "F.Paste")
			(net "GND")
			(options
				(clearance outline)
				(anchor circle)
			)
			(primitives
				(gr_poly
					(pts
						(arc
							(start -0.254 -0.1778)
							(mid -0.239121 -0.213721)
							(end -0.2032 -0.2286)
						)
						(arc
							(start 0.2032 -0.2286)
							(mid 0.239121 -0.213721)
							(end 0.254 -0.1778)
						)
						(arc
							(start 0.254 0.1778)
							(mid 0.239121 0.213721)
							(end 0.2032 0.2286)
						)
						(arc
							(start -0.2032 0.2286)
							(mid -0.239121 0.213721)
							(end -0.254 0.1778)
						)
					)
					(width 0)
					(fill yes)
				)
			)
		)
	)
	(footprint ""
		(layer "F.Cu")
		(at 18.6944 -67.134486 180)
		(property "Reference" "PC16"
			(at 0 0 180)
			(layer "F.SilkS")
			(hide yes)
			(effects
				(font
					(size 1.27 1.27)
				)
			)
		)
		(property "Value" "SCD022U16V2KX-3GP"
			(at 1.8923 -1.2065 180)
			(unlocked yes)
			(layer "F.Fab")
			(hide yes)
			(effects
				(font
					(size 1.016 1.016)
					(thickness 0.1524)
				)
			)
		)
		(property "Device Type" "C402H22"
			(at 1.8923 -2.7305 180)
			(unlocked yes)
			(layer "F.Fab")
			(hide yes)
			(effects
				(font
					(size 1.016 1.016)
					(thickness 0.1524)
				)
			)
		)
		(duplicate_pad_numbers_are_jumpers no)
		(fp_rect
			(start -0.381 0.7366)
			(end 0.381 -0.7366)
			(stroke
				(width 0)
				(type default)
			)
			(fill no)
			(layer "F.CrtYd")
		)
		(fp_rect
			(start -0.381 0.7366)
			(end 0.381 -0.7366)
			(stroke
				(width 0)
				(type default)
			)
			(fill no)
			(layer "F.Fab")
		)
		(pad "1" smd custom
			(at 0 -0.4572 180)
			(size 0.1143 0.1143)
			(layers "F.Cu" "F.Mask" "F.Paste")
			(net "VR_PVNN_ISUMN")
			(options
				(clearance outline)
				(anchor circle)
			)
			(primitives
				(gr_poly
					(pts
						(arc
							(start -0.254 -0.1778)
							(mid -0.239121 -0.213721)
							(end -0.2032 -0.2286)
						)
						(arc
							(start 0.2032 -0.2286)
							(mid 0.239121 -0.213721)
							(end 0.254 -0.1778)
						)
						(arc
							(start 0.254 0.1778)
							(mid 0.239121 0.213721)
							(end 0.2032 0.2286)
						)
						(arc
							(start -0.2032 0.2286)
							(mid -0.239121 0.213721)
							(end -0.254 0.1778)
						)
					)
					(width 0)
					(fill yes)
				)
			)
		)
		(pad "2" smd custom
			(at 0 0.4572 180)
			(size 0.1143 0.1143)
			(layers "F.Cu" "F.Mask" "F.Paste")
			(net "VR_PVNN_ISUMP")
			(options
				(clearance outline)
				(anchor circle)
			)
			(primitives
				(gr_poly
					(pts
						(arc
							(start -0.254 -0.1778)
							(mid -0.239121 -0.213721)
							(end -0.2032 -0.2286)
						)
						(arc
							(start 0.2032 -0.2286)
							(mid 0.239121 -0.213721)
							(end 0.254 -0.1778)
						)
						(arc
							(start 0.254 0.1778)
							(mid 0.239121 0.213721)
							(end 0.2032 0.2286)
						)
						(arc
							(start -0.2032 0.2286)
							(mid -0.239121 0.213721)
							(end -0.254 0.1778)
						)
					)
					(width 0)
					(fill yes)
				)
			)
		)
	)
	(footprint ""
		(layer "F.Cu")
		(at 20.0914 -23.4442 180)
		(property "Reference" "PR79"
			(at 0 0 180)
			(layer "F.SilkS")
			(hide yes)
			(effects
				(font
					(size 1.27 1.27)
				)
			)
		)
		(property "Value" "0R5J-5-GP"
			(at 0 -4.9022 180)
			(unlocked yes)
			(layer "F.Fab")
			(hide yes)
			(effects
				(font
					(size 1.016 1.016)
					(thickness 0.1524)
				)
			)
		)
		(property "Device Type" "R805H24"
			(at 0 -6.8072 180)
			(unlocked yes)
			(layer "F.Fab")
			(hide yes)
			(effects
				(font
					(size 1.016 1.016)
					(thickness 0.1524)
				)
			)
		)
		(duplicate_pad_numbers_are_jumpers no)
		(fp_line
			(start 0.6096 0)
			(end 0.2794 0)
			(stroke
				(width 0.3048)
				(type default)
			)
			(layer "F.SilkS")
		)
		(fp_line
			(start -0.2794 0)
			(end -0.6096 0)
			(stroke
				(width 0.3048)
				(type default)
			)
			(layer "F.SilkS")
		)
		(fp_poly
			(pts
				(xy -0.9017 1.4351) (xy 0.9017 1.4351) (xy 0.9017 -1.4351) (xy -0.9017 -1.4351)
			)
			(stroke
				(width 0)
				(type default)
			)
			(fill no)
			(layer "F.CrtYd")
		)
		(fp_poly
			(pts
				(xy 0.9017 1.4351) (xy 0.9017 -1.4351) (xy -0.9017 -1.4351) (xy -0.9017 1.4351)
			)
			(stroke
				(width 0)
				(type default)
			)
			(fill no)
			(layer "F.Fab")
		)
		(pad "1" smd rect
			(at 0 -0.8382 180)
			(size 1.5494 0.9398)
			(layers "F.Cu" "F.Mask" "F.Paste")
			(net "P1V0_VBST_RC")
		)
		(pad "2" smd rect
			(at 0 0.8382 180)
			(size 1.5494 0.9398)
			(layers "F.Cu" "F.Mask" "F.Paste")
			(net "P1V0_LX")
		)
	)
	(footprint ""
		(layer "F.Cu")
		(at 8.509 -56.515 90)
		(property "Reference" "C47"
			(at 0 0 90)
			(layer "F.SilkS")
			(hide yes)
			(effects
				(font
					(size 1.27 1.27)
				)
			)
		)
		(property "Value" "SCD1U16V2KX-3GP"
			(at 1.1811 -2.7051 90)
			(unlocked yes)
			(layer "F.Fab")
			(hide yes)
			(effects
				(font
					(size 1.016 1.016)
					(thickness 0.1524)
				)
			)
		)
		(property "Device Type" "C402H22"
			(at 1.1811 -4.2291 90)
			(unlocked yes)
			(layer "F.Fab")
			(hide yes)
			(effects
				(font
					(size 1.016 1.016)
					(thickness 0.1524)
				)
			)
		)
		(duplicate_pad_numbers_are_jumpers no)
		(fp_rect
			(start -0.381 0.7366)
			(end 0.381 -0.7366)
			(stroke
				(width 0)
				(type default)
			)
			(fill no)
			(layer "F.CrtYd")
		)
		(fp_rect
			(start -0.381 0.7366)
			(end 0.381 -0.7366)
			(stroke
				(width 0)
				(type default)
			)
			(fill no)
			(layer "F.Fab")
		)
		(pad "1" smd custom
			(at 0 -0.4572 90)
			(size 0.1143 0.1143)
			(layers "F.Cu" "F.Mask" "F.Paste")
			(net "P2E_CPU_NGFF_TX_DN13")
			(options
				(clearance outline)
				(anchor circle)
			)
			(primitives
				(gr_poly
					(pts
						(arc
							(start -0.254 -0.1778)
							(mid -0.239121 -0.213721)
							(end -0.2032 -0.2286)
						)
						(arc
							(start 0.2032 -0.2286)
							(mid 0.239121 -0.213721)
							(end 0.254 -0.1778)
						)
						(arc
							(start 0.254 0.1778)
							(mid 0.239121 0.213721)
							(end 0.2032 0.2286)
						)
						(arc
							(start -0.2032 0.2286)
							(mid -0.239121 0.213721)
							(end -0.254 0.1778)
						)
					)
					(width 0)
					(fill yes)
				)
			)
		)
		(pad "2" smd custom
			(at 0 0.4572 90)
			(size 0.1143 0.1143)
			(layers "F.Cu" "F.Mask" "F.Paste")
			(net "P2E_CPU_NGFF_C_TX_DN13")
			(options
				(clearance outline)
				(anchor circle)
			)
			(primitives
				(gr_poly
					(pts
						(arc
							(start -0.254 -0.1778)
							(mid -0.239121 -0.213721)
							(end -0.2032 -0.2286)
						)
						(arc
							(start 0.2032 -0.2286)
							(mid 0.239121 -0.213721)
							(end 0.254 -0.1778)
						)
						(arc
							(start 0.254 0.1778)
							(mid 0.239121 0.213721)
							(end 0.2032 0.2286)
						)
						(arc
							(start -0.2032 0.2286)
							(mid -0.239121 0.213721)
							(end -0.254 0.1778)
						)
					)
					(width 0)
					(fill yes)
				)
			)
		)
	)
	(footprint ""
		(layer "F.Cu")
		(at 156.718 -22.098)
		(property "Reference" "TP21"
			(at 0 0 0)
			(layer "F.SilkS")
			(hide yes)
			(effects
				(font
					(size 1.27 1.27)
				)
			)
		)
		(property "Value" "TPAD28-1-GP-U"
			(at 0.0508 -1.9304 0)
			(unlocked yes)
			(layer "F.Fab")
			(hide yes)
			(effects
				(font
					(size 1.016 1.016)
					(thickness 0.1524)
				)
			)
		)
		(property "Device Type" "TPAD28-1-U"
			(at 0.0508 -3.4544 0)
			(unlocked yes)
			(layer "F.Fab")
			(hide yes)
			(effects
				(font
					(size 1.016 1.016)
					(thickness 0.1524)
				)
			)
		)
		(duplicate_pad_numbers_are_jumpers no)
		(fp_poly
			(pts
				(arc
					(start 0.3556 0)
					(mid -0.3556 0)
					(end 0.3556 0)
				)
			)
			(stroke
				(width 0)
				(type default)
			)
			(fill no)
			(layer "F.CrtYd")
		)
		(fp_poly
			(pts
				(arc
					(start 0.9525 0)
					(mid -0.9525 0)
					(end 0.9525 0)
				)
			)
			(stroke
				(width 0)
				(type default)
			)
			(fill no)
			(layer "F.Fab")
		)
		(pad "1" smd circle
			(at 0 0)
			(size 0.7112 0.7112)
			(layers "F.Cu" "F.Mask" "F.Paste")
			(net "TP_FPGA_P111")
		)
	)
)
